FILE_TYPE = CONNECTIVITY;
{Allegro Design Entry HDL 16.6-p007 (v16-6-112F) 10/10/2012}
"PAGE_NUMBER" = 200;
0"NC";
1"AGND_HSC\g";
2"P12V_STBY\g";
3"GND\g";
4"P12V_STBY\g";
5"AGND_HSC\g";
6"P3V3_STBY\g";
7"GND\g";
8"P3V3_STBY\g";
9"GND\g";
10"AGND_HSC\g";
11"AGND_HSC\g";
12"GND\g";
13"P12V_STBY\g";
14"AGND_HSC\g";
15"P3V3_STBY\g";
16"P3V3_STBY\g";
17"GND\g";
18"GND\g";
19"P3V3_STBY\g";
20"GND\g";
21"P3V3_STBY\g";
22"P3V3_STBY\g";
23"AGND_HSC\g";
24"AGND_HSC\g";
25"GND\g";
26"P12V_STBY\g";
27"GND\g";
28"GND\g";
29"P3V3_STBY\g";
30"AGND_HSC\g";
31"AGND_HSC\g";
32"AGND_HSC\g";
33"P12V_PSU\g";
34"P12V_STBY\g";
35"P3V3_STBY\g";
36"AGND_HSC\g";
37"GND\g";
38"A_P12V_STBY_FP_TRIGGER";
39"A_P12V_STBY_FPH_GATE";
40"FM_UV_ADR_TRIGGER_N";
41"A_P12V_STBY_ADR_TRIGGER";
42"FM_OC_DETECT_N";
43"BMC_UV_HIGH_SET";
44"A_P12V_STBY_FP_TRIGGER";
45"UV_HIGH_SET_N";
46"IRQ_OC_DETECT_N";
47"A_HSC_INAP";
48"A_HSC_TIMER_R";
49"A_HSC_TIMER";
50"A_HSC_CSOUT";
51"A_HSC_LOW";
52"A_HSC_HIGH";
53"A_HSC_LOW_GATE";
54"A_HSC_MOP";
55"A_HSC_MON";
56"IRQ_UV_DETECT_N";
57"A_HSC_C";
58"P12V_HSC_SENP0"VOLTAGE"+12V";
59"P12V_HSC_SENP1"VOLTAGE"+12V";
60"P12V_HSC_SENN1"VOLTAGE"+12V";
61"A_HSC_GATE3_R";
62"A_HSC_GATE2_R";
63"A_HSC_GATE1_R";
64"FM_OC_DETECT_EN_N";
65"A_HSC_LOW_DRAIN";
66"PWRGD_DSW_PWROK";
67"FM_DISABLE_FAN_N";
68"P12V_HSC_SENN0"VOLTAGE"+12V";
69"P12V_MB0_SW"VOLTAGE"+12V";
70"A_HSC_GATE";
71"A_HSC_HSN";
72"A_HSC_HSP";
73"FM_OC_DETECT_EN";
74"FM_HSC_TIMER_EXP_N";
75"AGND_HSC\g";
%"TTL1G126_A"
"1","(-2900,2225)","0","mstr_ttl","I103";
;
CDS_SEC"1"
CDS_LIB"mstr_ttl"
PACK_TYPE"SOT"
CDS_LOCATION"U1D1"
ROOM"HOT_SWAP"
SEC_TYPE"SOT"
SEC"1"
PART_NUMBER"A79322-001"
VALUE"74HC1G126"
LOCATION"U1D1"
MATERIAL"IC"
POWER_GROUP"GND=GND"
POWER_GROUP"VCC=P3V3_STBY";
"OE"
$PN"1"73;
"Y"
$PN"4"42;
"A"
$PN"2"46;
%"AGND0"
"1","(-1650,-475)","0","mstr_symbols","I106";
;
BODY_TYPE"PLUMBING"
ROOM"VR_P3V3"
BOM_COST"MIO_VRD_MAIN"
CDS_LIB"mstr_symbols"
VOLTAGE"0"
HDL_POWER"AGND_HSC";
"A"1;
%"RES"
"2","(-1650,250)","0","mstr_discrete","I107";
;
CDS_SEC"1"
CDS_LIB"mstr_discrete"
CDS_LOCATION"R9P13"
ROOM"HOT_SWAP"
SEC"1"
SEC_TYPE"0402"
WATTAGE"1/16W"
VALUE"274K"
LOCATION"R9P13"
MATERIAL"CHIP"
PACK_TYPE"0402"
TOLERANCE"1.0%"
PART_NUMBER"G21796-331";
"A"
$PN"1"2;
"B"
$PN"2"38;
%"RES"
"2","(-1650,-150)","0","mstr_discrete","I108";
;
CDS_SEC"1"
ROOM"HOT_SWAP"
SEC"1"
SEC_TYPE"0402"
CDS_LOCATION"R9P11"
CDS_LIB"mstr_discrete"
WATTAGE"1/16W"
MATERIAL"CHIP"
PART_NUMBER"G21796-016"
LOCATION"R9P11"
TOLERANCE"1%"
VALUE"10.0K"
PACK_TYPE"0402";
"A"
$PN"1"38;
"B"
$PN"2"1;
%"P12V_STBY"
"1","(-1650,525)","0","mstr_symbols","I109";
;
HDL_POWER"P12V_STBY"
BODY_TYPE"PLUMBING"
VOLTAGE"12.0V"
SIZE"1B"
CDS_LIB"mstr_symbols";
"G\NAC"2;
%"GND"
"1","(-3075,-475)","0","mstr_symbols","I114";
;
SIZE"1B"
CDS_LIB"mstr_symbols"
VOLTAGE"0.0V"
BODY_TYPE"PLUMBING"
HDL_POWER"GND";
"A\NAC"3;
%"P12V_STBY"
"1","(-1975,1025)","0","mstr_symbols","I144";
;
CDS_LIB"mstr_symbols"
SIZE"1B"
VOLTAGE"12.0V"
BODY_TYPE"PLUMBING"
HDL_POWER"P12V_STBY";
"G\NAC"4;
%"RES"
"2","(-1975,800)","0","mstr_discrete","I145";
;
CDS_SEC"1"
SEC_TYPE"0402"
SEC"1"
CDS_LOCATION"R9P7"
ROOM"HOT_SWAP"
CDS_LIB"mstr_discrete"
VALUE"249K"
PACK_TYPE"0402"
LOCATION"R9P7"
WATTAGE"1/16W"
MATERIAL"CHIP"
PART_NUMBER"G21796-189"
TOLERANCE"1.0%";
"A"
$PN"1"4;
"B"
$PN"2"41;
%"RES"
"2","(-1975,375)","0","mstr_discrete","I146";
;
CDS_SEC"1"
SEC_TYPE"0402"
SEC"1"
ROOM"HOT_SWAP"
CDS_LOCATION"R9P9"
CDS_LIB"mstr_discrete"
PART_NUMBER"G21796-016"
PACK_TYPE"0402"
VALUE"10.0K"
TOLERANCE"1%"
MATERIAL"CHIP"
LOCATION"R9P9"
WATTAGE"1/16W";
"A"
$PN"1"41;
"B"
$PN"2"5;
%"AGND0"
"1","(-1975,25)","0","mstr_symbols","I147";
;
VOLTAGE"0"
CDS_LIB"mstr_symbols"
BOM_COST"MIO_VRD_MAIN"
ROOM"VR_P3V3"
BODY_TYPE"PLUMBING"
HDL_POWER"AGND_HSC";
"A"5;
%"RES"
"2","(600,1100)","0","mstr_discrete","I149";
;
CDS_SEC"1"
SEC_TYPE"0402"
SEC"1"
ROOM"HOT_SWAP"
CDS_LOCATION"R9P6"
CDS_LIB"mstr_discrete"
MATERIAL"CHIP"
WATTAGE"1/16W"
VALUE"10.0K"
LOCATION"R9P6"
PART_NUMBER"G21796-016"
TOLERANCE"1%"
PACK_TYPE"0402";
"A"
$PN"1"6;
"B"
$PN"2"40;
%"P3V3_STBY"
"1","(600,1400)","0","mstr_symbols","I150";
;
VOLTAGE"+3.3V"
SIZE"1B"
CDS_LIB"mstr_symbols"
BODY_TYPE"PLUMBING"
HDL_POWER"P3V3_STBY";
"G\NAC"6;
%"RES"
"1","(1350,1875)","0","mstr_discrete","I154";
;
CDS_SEC"1"
SEC_TYPE"0402"
SEC"1"
ROOM"HOT_SWAP"
CDS_LOCATION"R1D51"
CDS_LIB"mstr_discrete"
PART_NUMBER"G21796-066"
LOCATION"R1D51"
TOLERANCE"1%"
WATTAGE"1/16W"
MATERIAL"CHIP"
PACK_TYPE"0402"
VALUE"10.0";
"B"
$PN"2"70;
"A"
$PN"1"57;
%"CAP"
"1","(900,1675)","0","mstr_discrete","I155";
;
CDS_SEC"1"
SEC_TYPE"1206"
SEC"1"
CDS_LOCATION"C1E2"
CDS_LIB"mstr_discrete"
TOLERANCE"20%"
MATERIAL"X7R"
PART_NUMBER"108427-047"
LOCATION"C1E2"
VALUE"0.068UF"
VOLTAGE"50V"
PACK_TYPE"1206";
"A"
$PN"1"57;
"B"
$PN"2"7;
%"GND"
"1","(900,1450)","0","mstr_symbols","I156";
;
VOLTAGE"0.0V"
CDS_LIB"mstr_symbols"
SIZE"1B"
BODY_TYPE"PLUMBING"
HDL_POWER"GND";
"A\NAC"7;
%"P3V3_STBY"
"1","(-1650,2525)","0","mstr_symbols","I157";
;
CDS_LIB"mstr_symbols"
SIZE"1B"
VOLTAGE"+3.3V"
BODY_TYPE"PLUMBING"
HDL_POWER"P3V3_STBY";
"G\NAC"8;
%"RES"
"2","(-1650,2350)","0","mstr_discrete","I158";
;
CDS_SEC"1"
CDS_LIB"mstr_discrete"
CDS_LOCATION"R1D22"
ROOM"HOT_SWAP"
SEC"1"
SEC_TYPE"0402"
VALUE"10.0K"
TOLERANCE"1%"
MATERIAL"CHIP"
WATTAGE"1/16W"
LOCATION"R1D22"
PART_NUMBER"G21796-016"
PACK_TYPE"0402";
"A"
$PN"1"8;
"B"
$PN"2"42;
%"TPS3700"
"1","(-350,350)","0","mstr_vreg","I163";
;
CDS_SEC"1"
CDS_LMAN_SYM_OUTLINE"-250,200,250,-200"
CDS_LIB"mstr_vreg"
PACK_TYPE"SM"
SEC_TYPE"SM"
SEC"1"
CDS_LOCATION"U9P1"
MATERIAL"IC"
PART_NUMBER"H69492-001"
LOCATION"U9P1";
"VDD"
$PN"2"4;
"OUTB"
$PN"1"39;
"OUTA"
$PN"6"40;
"INBN"
$PN"3"38;
"INAP"
$PN"4"41;
"GND"
$PN"5"37;
%"TPS3700"
"1","(-3100,3125)","0","mstr_vreg","I170";
;
CDS_SEC"1"
CDS_LMAN_SYM_OUTLINE"-250,200,250,-200"
CDS_LIB"mstr_vreg"
PACK_TYPE"SM"
SEC_TYPE"SM"
SEC"1"
CDS_LOCATION"U1D2"
PART_NUMBER"H69492-001"
LOCATION"U1D2"
MATERIAL"IC";
"VDD"
$PN"2"13;
"OUTB"
$PN"1"46;
"OUTA"
$PN"6"53;
"INBN"
$PN"3"52;
"INAP"
$PN"4"51;
"GND"
$PN"5"12;
%"RES"
"2","(-4150,2825)","0","mstr_discrete","I172";
;
CDS_SEC"1"
SEC_TYPE"0402"
SEC"1"
CDS_LIB"mstr_discrete"
CDS_LOCATION"R1D20"
LOCATION"R1D20"
PART_NUMBER"G21796-109"
VALUE"150.0K"
TOLERANCE"1%"
PACK_TYPE"0402"
MATERIAL"CHIP"
WATTAGE"1/16W";
"A"
$PN"1"50;
"B"
$PN"2"52;
%"RES"
"2","(-4575,3400)","0","mstr_discrete","I173";
;
CDS_SEC"1"
SEC_TYPE"0402"
SEC"1"
CDS_LOCATION"R1D14"
CDS_LIB"mstr_discrete"
PART_NUMBER"G21796-099"
WATTAGE"1/16W"
LOCATION"R1D14"
TOLERANCE"1%"
MATERIAL"CHIP"
PACK_TYPE"0402"
VALUE"105.0K";
"A"
$PN"1"50;
"B"
$PN"2"51;
%"RES"
"2","(-4575,2800)","0","mstr_discrete","I174";
;
CDS_SEC"1"
ROOM"HOT_SWAP"
CDS_LOCATION"R1D12"
SEC"1"
SEC_TYPE"0402"
CDS_LIB"mstr_discrete"
PART_NUMBER"G21796-016"
TOLERANCE"1%"
VALUE"10.0K"
LOCATION"R1D12"
WATTAGE"1/16W"
PACK_TYPE"0402"
MATERIAL"CHIP";
"A"
$PN"1"51;
"B"
$PN"2"11;
%"RES"
"2","(-4150,2450)","0","mstr_discrete","I175";
;
CDS_SEC"1"
SEC_TYPE"0402"
SEC"1"
CDS_LOCATION"R1D19"
ROOM"HOT_SWAP"
CDS_LIB"mstr_discrete"
LOCATION"R1D19"
PART_NUMBER"G21796-016"
VALUE"10.0K"
TOLERANCE"1%"
PACK_TYPE"0402"
MATERIAL"CHIP"
WATTAGE"1/16W";
"A"
$PN"1"52;
"B"
$PN"2"10;
%"GND"
"1","(-50,50)","0","mstr_symbols","I178";
;
SIZE"1B"
CDS_LIB"mstr_symbols"
VOLTAGE"0.0V"
BODY_TYPE"PLUMBING"
HDL_POWER"GND";
"A\NAC"37;
%"GND"
"1","(550,-400)","0","mstr_symbols","I179";
;
CDS_LIB"mstr_symbols"
SIZE"1B"
VOLTAGE"0.0V"
BODY_TYPE"PLUMBING"
HDL_POWER"GND";
"A\NAC"9;
%"AGND0"
"1","(-4150,2150)","0","mstr_symbols","I180";
;
VOLTAGE"0"
BOM_COST"MIO_VRD_MAIN"
CDS_LIB"mstr_symbols"
ROOM"VR_P3V3"
BODY_TYPE"PLUMBING"
HDL_POWER"AGND_HSC";
"A"10;
%"AGND0"
"1","(-4575,2500)","0","mstr_symbols","I181";
;
VOLTAGE"0"
BOM_COST"MIO_VRD_MAIN"
CDS_LIB"mstr_symbols"
ROOM"VR_P3V3"
BODY_TYPE"PLUMBING"
HDL_POWER"AGND_HSC";
"A"11;
%"GND"
"1","(-2750,2800)","0","mstr_symbols","I183";
;
CDS_LIB"mstr_symbols"
SIZE"1B"
VOLTAGE"0.0V"
BODY_TYPE"PLUMBING"
HDL_POWER"GND";
"A\NAC"12;
%"P12V_STBY"
"1","(-3800,3700)","0","mstr_symbols","I184";
;
SIZE"1B"
CDS_LIB"mstr_symbols"
VOLTAGE"12.0V"
BODY_TYPE"PLUMBING"
HDL_POWER"P12V_STBY";
"G\NAC"13;
%"CAP_A"
"1","(-825,775)","2","dev_discrete","I185";
;
ROOM"HOT_SWAP"
CDS_LOCATION"C9P6"
CDS_LIB"dev_discrete"
CDS_SEC"1"
SEC"1"
SEC_TYPE"0402V"
TOLERANCE"10%"
VOLTAGE"16V"
PACK_TYPE"0402V"
VALUE"0.1UF"
PART_NUMBER"A36096-030"
MATERIAL"X7R"
LOCATION"C9P6";
"B"
$PN"2"75;
"A"
$PN"1"4;
%"AGND0"
"1","(-825,625)","0","mstr_symbols","I186";
;
VOLTAGE"0"
CDS_LIB"mstr_symbols"
BOM_COST"MIO_VRD_MAIN"
ROOM"VR_P3V3"
BODY_TYPE"PLUMBING"
HDL_POWER"AGND_HSC";
"A"75;
%"CAP_A"
"1","(-3800,3425)","2","dev_discrete","I187";
;
SEC"1"
SEC_TYPE"0402V"
ROOM"HOT_SWAP"
CDS_SEC"1"
CDS_LIB"dev_discrete"
CDS_LOCATION"C1D9"
LOCATION"C1D9"
VALUE"0.1UF"
TOLERANCE"10%"
PACK_TYPE"0402V"
VOLTAGE"16V"
PART_NUMBER"A36096-030"
MATERIAL"X7R";
"B"
$PN"2"14;
"A"
$PN"1"13;
%"AGND0"
"1","(-3800,3175)","0","mstr_symbols","I188";
;
CDS_LIB"mstr_symbols"
VOLTAGE"0"
ROOM"VR_P3V3"
BOM_COST"MIO_VRD_MAIN"
BODY_TYPE"PLUMBING"
HDL_POWER"AGND_HSC";
"A"14;
%"RES"
"2","(-2600,3525)","0","mstr_discrete","I189";
;
CDS_SEC"1"
CDS_LOCATION"R1D10"
CDS_LIB"mstr_discrete"
SEC_TYPE"0402"
SEC"1"
ROOM"HOT_SWAP"
LOCATION"R1D10"
VALUE"10.0K"
TOLERANCE"1%"
PACK_TYPE"0402"
MATERIAL"CHIP"
WATTAGE"1/16W"
PART_NUMBER"G21796-016";
"A"
$PN"1"15;
"B"
$PN"2"53;
%"P3V3_STBY"
"1","(-2600,3875)","0","mstr_symbols","I190";
;
VOLTAGE"+3.3V"
SIZE"1B"
CDS_LIB"mstr_symbols"
BODY_TYPE"PLUMBING"
HDL_POWER"P3V3_STBY";
"G\NAC"15;
%"RES"
"2","(-2825,3500)","0","mstr_discrete","I191";
;
CDS_SEC"1"
ROOM"HOT_SWAP"
CDS_LOCATION"R1D23"
SEC"1"
SEC_TYPE"0402"
CDS_LIB"mstr_discrete"
TOLERANCE"1%"
MATERIAL"CHIP"
PACK_TYPE"0402"
PART_NUMBER"G21796-016"
WATTAGE"1/16W"
VALUE"10.0K"
LOCATION"R1D23";
"A"
$PN"1"15;
"B"
$PN"2"46;
%"RES"
"2","(275,1075)","0","mstr_discrete","I192";
;
CDS_SEC"1"
SEC_TYPE"0402"
SEC"1"
CDS_LOCATION"R9P10"
ROOM"HOT_SWAP"
CDS_LIB"mstr_discrete"
TOLERANCE"1%"
LOCATION"R9P10"
VALUE"10.0K"
WATTAGE"1/16W"
MATERIAL"CHIP"
PART_NUMBER"G21796-016"
PACK_TYPE"0402";
"A"
$PN"1"16;
"B"
$PN"2"39;
%"P3V3_STBY"
"1","(275,1400)","0","mstr_symbols","I194";
;
VOLTAGE"+3.3V"
SIZE"1B"
CDS_LIB"mstr_symbols"
BODY_TYPE"PLUMBING"
HDL_POWER"P3V3_STBY";
"G\NAC"16;
%"FET_N_DUAL"
"5","(-2150,3325)","0","mstr_discrete","I196";
;
CDS_SEC"1"
PACK_TYPE"SMLF"
SEC_TYPE"SMLF"
SEC"1"
CDS_LOCATION"Q9P1"
ROOM"HOT_SWAP"
CDS_LIB"mstr_discrete"
PART_NUMBER"D24280-001"
VALUE"2N7002DW"
MATERIAL"FET"
LOCATION"Q9P1";
"GATE <SIZE -1..0>"
$PN"2"53;
"SOURCE <SIZE-1..0>"
$PN"1"17;
"DRAIN <SIZE -1..0>"
$PN"6"65;
%"GND"
"1","(-2150,3000)","0","mstr_symbols","I197";
;
VOLTAGE"0.0V"
SIZE"1B"
CDS_LIB"mstr_symbols"
BODY_TYPE"PLUMBING"
HDL_POWER"GND";
"A\NAC"17;
%"RES"
"1","(-1900,3850)","0","mstr_discrete","I198";
;
CDS_SEC"1"
CDS_LIB"mstr_discrete"
SEC"1"
SEC_TYPE"0402"
ROOM"HOT_SWAP"
CDS_LOCATION"R9P15"
MATERIAL"EMPTY"
TOLERANCE"5%"
PACK_TYPE"0402"
LOCATION"R9P15"
PART_NUMBER"G21497-005"
VALUE"0.0"
WATTAGE"1/16W";
"B"
$PN"2"46;
"A"
$PN"1"65;
%"FET_N_DUAL"
"5","(550,-100)","0","mstr_discrete","I199";
;
CDS_SEC"2"
SEC_TYPE"SMLF"
SEC"2"
ROOM"HOT_SWAP"
PACK_TYPE"SMLF"
CDS_LOCATION"Q9P1"
CDS_LIB"mstr_discrete"
PART_NUMBER"D24280-001"
LOCATION"Q9P1"
VALUE"2N7002DW"
MATERIAL"FET";
"GATE <SIZE -1..0>"
$PN"5"39;
"SOURCE <SIZE-1..0>"
$PN"4"9;
"DRAIN <SIZE -1..0>"
$PN"3"56;
%"TPS3700"
"1","(-3425,-150)","0","mstr_vreg","I200";
;
PACK_TYPE"SM"
CDS_SEC"1"
$SEC"1"
CDS_LOCATION"U9P2"
CDS_LIB"mstr_vreg"
CDS_LMAN_SYM_OUTLINE"-250,200,250,-200"
MATERIAL"IC"
PART_NUMBER"H69492-001"
LOCATION"U9P2";
"VDD"
$PN"2"35;
"OUTB"
$PN"1"74;
"OUTA"
$PN"6"66;
"INBN"
$PN"3"48;
"INAP"
$PN"4"47;
"GND"
$PN"5"3;
%"CAP_A"
"1","(-3450,500)","2","dev_discrete","I201";
;
SEC"1"
SEC_TYPE"0402V"
CDS_SEC"1"
CDS_LOCATION"C9P11"
ROOM"HOT_SWAP"
CDS_LIB"dev_discrete"
MATERIAL"X7R"
TOLERANCE"10%"
PACK_TYPE"0402V"
PART_NUMBER"A36096-030"
LOCATION"C9P11"
VALUE"0.1UF"
VOLTAGE"16V";
"B"
$PN"2"18;
"A"
$PN"1"35;
%"GND"
"1","(-3450,225)","0","mstr_symbols","I202";
;
CDS_LIB"mstr_symbols"
SIZE"1B"
VOLTAGE"0.0V"
BODY_TYPE"PLUMBING"
HDL_POWER"GND";
"A\NAC"18;
%"FET_N"
"8","(-3500,1300)","0","mstr_discrete","I203";
;
CDS_SEC"1"
CDS_LIB"mstr_discrete"
CDS_LOCATION"Q1D2"
SEC"1"
SEC_TYPE"SOT23LF"
ROOM"HOT_SWAP"
PACK_TYPE"SOT23LF"
LOCATION"Q1D2"
VALUE"2N7002"
MATERIAL"FET"
PART_NUMBER"C79254-001";
"GATE"
$PN"1"64;
"DRN"
$PN"3"73;
"SRC"
$PN"2"20;
%"RES"
"2","(-3500,1750)","0","mstr_discrete","I204";
;
CDS_SEC"1"
ROOM"HOT_SWAP"
SEC"1"
SEC_TYPE"0402"
CDS_LOCATION"R1D21"
CDS_LIB"mstr_discrete"
LOCATION"R1D21"
VALUE"4.75K"
TOLERANCE"1%"
PART_NUMBER"G21796-072"
PACK_TYPE"0402"
WATTAGE"1/16W"
MATERIAL"CHIP";
"A"
$PN"1"19;
"B"
$PN"2"73;
%"P3V3_STBY"
"1","(-3500,1950)","0","mstr_symbols","I205";
;
SIZE"1B"
CDS_LIB"mstr_symbols"
VOLTAGE"3.3V"
BODY_TYPE"PLUMBING"
HDL_POWER"P3V3_STBY";
"G\NAC"19;
%"GND"
"1","(-3500,925)","0","mstr_symbols","I206";
;
VOLTAGE"0.0V"
SIZE"1B"
CDS_LIB"mstr_symbols"
BODY_TYPE"PLUMBING"
HDL_POWER"GND";
"A\NAC"20;
%"RES"
"2","(1750,225)","0","mstr_discrete","I210";
;
CDS_SEC"1"
SEC_TYPE"0402"
SEC"1"
CDS_LOCATION"R9P4"
ROOM"HOT_SWAP"
CDS_LIB"mstr_discrete"
PART_NUMBER"G21796-344"
LOCATION"R9P4"
VALUE"2.7K"
TOLERANCE"1%"
PACK_TYPE"0402"
MATERIAL"CHIP"
WATTAGE"1/16W";
"A"
$PN"1"21;
"B"
$PN"2"56;
%"P3V3_STBY"
"1","(1750,450)","0","mstr_symbols","I211";
;
VOLTAGE"+3.3V"
SIZE"1B"
CDS_LIB"mstr_symbols"
BODY_TYPE"PLUMBING"
HDL_POWER"P3V3_STBY";
"G\NAC"21;
%"DIODE"
"1","(1000,675)","2","mstr_discrete","I213";
;
CDS_SEC"1"
CDS_LOCATION"CR9P2"
SEC"1"
SEC_TYPE"SMLF"
CDS_LIB"mstr_discrete"
LOCATION"CR9P2"
PART_NUMBER"C73510-001"
VALUE"BAT54WS"
PACK_TYPE"SMLF"
MATERIAL"IC";
"C"
$PN"1"40;
"A"
$PN"2"67;
%"DIODE"
"1","(1050,175)","2","mstr_discrete","I214";
;
CDS_SEC"1"
CDS_LIB"mstr_discrete"
SEC_TYPE"SMLF"
SEC"1"
CDS_LOCATION"CR9P1"
PACK_TYPE"SMLF"
VALUE"BAT54WS"
MATERIAL"IC"
PART_NUMBER"C73510-001"
LOCATION"CR9P1";
"C"
$PN"1"56;
"A"
$PN"2"67;
%"RES"
"2","(1500,1125)","0","mstr_discrete","I215";
;
CDS_SEC"1"
SEC_TYPE"0402"
SEC"1"
CDS_LOCATION"R9P5"
ROOM"HOT_SWAP"
CDS_LIB"mstr_discrete"
LOCATION"R9P5"
VALUE"10.0K"
TOLERANCE"1%"
MATERIAL"CHIP"
WATTAGE"1/16W"
PART_NUMBER"G21796-016"
PACK_TYPE"0402";
"A"
$PN"1"22;
"B"
$PN"2"67;
%"P3V3_STBY"
"1","(1500,1400)","0","mstr_symbols","I216";
;
VOLTAGE"+3.3V"
SIZE"1B"
CDS_LIB"mstr_symbols"
BODY_TYPE"PLUMBING"
HDL_POWER"P3V3_STBY";
"G\NAC"22;
%"AGND0"
"1","(-4400,-650)","0","mstr_symbols","I217";
;
ROOM"VR_P3V3"
CDS_LIB"mstr_symbols"
BOM_COST"MIO_VRD_MAIN"
VOLTAGE"0"
BODY_TYPE"PLUMBING"
HDL_POWER"AGND_HSC";
"A"23;
%"RES"
"2","(-3950,-475)","0","mstr_discrete","I218";
;
CDS_SEC"1"
SEC_TYPE"0402"
SEC"1"
CDS_LOCATION"R9P12"
CDS_LIB"mstr_discrete"
ROOM"HOT_SWAP"
LOCATION"R9P12"
VALUE"4.99K"
WATTAGE"1/16W"
TOLERANCE"1%"
PART_NUMBER"G21796-013"
PACK_TYPE"0402"
MATERIAL"CHIP";
"A"
$PN"1"47;
"B"
$PN"2"24;
%"AGND0"
"1","(-3950,-675)","0","mstr_symbols","I219";
;
CDS_LIB"mstr_symbols"
VOLTAGE"0"
BOM_COST"MIO_VRD_MAIN"
ROOM"VR_P3V3"
BODY_TYPE"PLUMBING"
HDL_POWER"AGND_HSC";
"A"24;
%"DIODE"
"1","(2750,3275)","1","mstr_discrete","I220";
;
CDS_SEC"1"
CDS_LOCATION"CR1F5"
SEC"1"
SEC_TYPE"SM"
CDS_LIB"mstr_discrete"
MATERIAL"EMPTY"
VALUE"MBRS340T3G"
PACK_TYPE"SM"
LOCATION"CR1F5"
PART_NUMBER"C81983-002";
"C"
$PN"1"34;
"A"
$PN"2"25;
%"GND"
"1","(2750,3000)","0","mstr_symbols","I221";
;
VOLTAGE"0.0V"
SIZE"1B"
CDS_LIB"mstr_symbols"
BODY_TYPE"PLUMBING"
HDL_POWER"GND";
"A\NAC"25;
%"RES"
"2","(-3950,200)","2","mstr_discrete","I222";
;
CDS_LOCATION"R9P33"
CDS_SEC"1"
$SEC"1"
ROOM"HOT_SWAP"
CDS_LIB"mstr_discrete"
TOLERANCE"1%"
LOCATION"R9P33"
PART_NUMBER"G21796-010"
VALUE"100.0K"
PACK_TYPE"0402"
MATERIAL"CHIP"
WATTAGE"1/16W";
"A"
$PN"1"26;
"B"
$PN"2"47;
%"P12V_STBY"
"1","(-3950,700)","0","mstr_symbols","I223";
;
VOLTAGE"12.0V"
SIZE"1B"
CDS_LIB"mstr_symbols"
BODY_TYPE"PLUMBING"
HDL_POWER"P12V_STBY";
"G\NAC"26;
%"FET_N"
"8","(-1500,1675)","0","mstr_discrete","I225";
;
CDS_SEC"1"
$SEC"1"
CDS_LOCATION"Q6W1"
PACK_TYPE"SOT23LF"
ROOM"HOT_SWAP"
CDS_LIB"mstr_discrete"
PART_NUMBER"C79254-001"
MATERIAL"FET"
VALUE"2N7002"
LOCATION"Q6W1";
"GATE"
$PN"1"43;
"DRN"
$PN"3"45;
"SRC"
$PN"2"27;
%"GND"
"1","(-1500,1300)","0","mstr_symbols","I227";
;
CDS_LIB"mstr_symbols"
VOLTAGE"0.0V"
SIZE"1B"
BODY_TYPE"PLUMBING"
HDL_POWER"GND";
"A\NAC"27;
%"RES"
"2","(-1950,1825)","0","mstr_discrete","I229";
;
CDS_SEC"1"
$SEC"1"
CDS_LOCATION"R6W1"
CDS_LIB"mstr_discrete"
ROOM"PVCCIN_CPU1_VR"
WATTAGE"1/16W"
VALUE"100.0K"
LOCATION"R6W1"
MATERIAL"CHIP"
PART_NUMBER"G21796-160"
PACK_TYPE"0402"
TOLERANCE"1%";
"A"
$PN"1"29;
"B"
$PN"2"43;
%"RES"
"2","(-1950,1425)","0","mstr_discrete","I230";
;
CDS_SEC"1"
$SEC"1"
CDS_LOCATION"R6W2"
CDS_LIB"mstr_discrete"
ROOM"HOT_SWAP"
STATUS"NOPOP"
VALUE"10.0K"
TOLERANCE"1%"
PART_NUMBER"G21796-016"
MATERIAL"CHIP"
PACK_TYPE"0402"
LOCATION"R6W2"
WATTAGE"1/16W";
"A"
$PN"1"43;
"B"
$PN"2"28;
%"GND"
"1","(-1950,1225)","0","mstr_symbols","I231";
;
SIZE"1B"
VOLTAGE"0.0V"
CDS_LIB"mstr_symbols"
BODY_TYPE"PLUMBING"
HDL_POWER"GND";
"A\NAC"28;
%"P3V3_STBY"
"1","(-1950,2050)","0","mstr_symbols","I232";
;
VOLTAGE"+3.3V"
SIZE"1B"
CDS_LIB"mstr_symbols"
BODY_TYPE"PLUMBING"
HDL_POWER"P3V3_STBY";
"G\NAC"29;
%"SC22P50V2JN-4GP"
"1","(-700,-100)","0","w_hdl","I235";
;
STATUS"NOPOP"
CDS_SEC"1"
$SEC"1"
CDS_LOCATION"C9W1"
PACK_TYPE"SMD-BCG"
PART_NUMBER"78.22034.1FL"
CDS_LIB"w_hdl"
CDS_LMAN_SYM_OUTLINE"-50,25,50,-25"
VALUE"SC22P50V2JN-4GP"
LOCATION"C9W1";
"2"
$PN"2"30;
"1"
$PN"1"38;
%"SC22P50V2JN-4GP"
"1","(-1050,175)","0","w_hdl","I236";
;
STATUS"NOPOP"
CDS_SEC"1"
$SEC"1"
CDS_LOCATION"C9W2"
CDS_LMAN_SYM_OUTLINE"-50,25,50,-25"
CDS_LIB"w_hdl"
PART_NUMBER"78.22034.1FL"
PACK_TYPE"SMD-BCG"
LOCATION"C9W2"
VALUE"SC22P50V2JN-4GP";
"2"
$PN"2"36;
"1"
$PN"1"41;
%"AGND0"
"1","(-700,-250)","0","mstr_symbols","I237";
;
CDS_LIB"mstr_symbols"
VOLTAGE"0"
BOM_COST"MIO_VRD_MAIN"
ROOM"VR_P3V3"
BODY_TYPE"PLUMBING"
HDL_POWER"AGND_HSC";
"A"30;
%"AGND0"
"1","(-1050,-100)","0","mstr_symbols","I238";
;
VOLTAGE"0"
BOM_COST"MIO_VRD_MAIN"
ROOM"VR_P3V3"
BODY_TYPE"PLUMBING"
CDS_LIB"mstr_symbols"
HDL_POWER"AGND_HSC";
"A"36;
%"232KR2F-2-GP"
"1","(-800,1950)","1","w_hdl","I239";
;
CDS_SEC"1"
$SEC"1"
CDS_LOCATION"R6W3"
PACK_TYPE"SMD-RG1"
PART_NUMBER"64.23235.L0L"
CDS_LIB"w_hdl"
CDS_LMAN_SYM_OUTLINE"-50,75,50,-75"
VALUE"232KR2F-2-GP"
LOCATION"R6W3";
"2"
$PN"2"44;
"1"
$PN"1"45;
%"CAP_A"
"1","(-1025,3425)","0","dev_discrete","I36";
;
CDS_SEC"1"
SEC"1"
SEC_TYPE"0402V"
ROOM"HOT_SWAP"
CDS_LOCATION"C9P17"
CDS_LIB"dev_discrete"
PART_NUMBER"A36096-030"
LOCATION"C9P17"
VALUE"0.1UF"
TOLERANCE"10%"
VOLTAGE"16V"
MATERIAL"EMPTY"
PACK_TYPE"0402V";
"B"
$PN"2"31;
"A"
$PN"1"55;
%"AGND0"
"1","(-1025,3225)","0","mstr_symbols","I39";
;
BOM_COST"MIO_VRD_MAIN"
CDS_LIB"mstr_symbols"
VOLTAGE"0"
ROOM"VR_P3V3"
BODY_TYPE"PLUMBING"
HDL_POWER"AGND_HSC";
"A"31;
%"CAP_A"
"1","(-675,3000)","0","dev_discrete","I40";
;
$SEC"1"
CDS_SEC"1"
CDS_LOCATION"C9P16"
ROOM"HOT_SWAP"
CDS_LIB"dev_discrete"
PACK_TYPE"0402V"
PART_NUMBER"A36096-030"
VOLTAGE"16V"
TOLERANCE"10%"
MATERIAL"EMPTY"
LOCATION"C9P16"
VALUE"0.1UF";
"B"
$PN"2"32;
"A"
$PN"1"54;
%"AGND0"
"1","(-675,2725)","0","mstr_symbols","I41";
;
VOLTAGE"0"
CDS_LIB"mstr_symbols"
BOM_COST"MIO_VRD_MAIN"
ROOM"VR_P3V3"
BODY_TYPE"PLUMBING"
HDL_POWER"AGND_HSC";
"A"32;
%"CAP_A"
"1","(-175,3425)","0","dev_discrete","I42";
;
$SEC"1"
CDS_SEC"1"
ROOM"HOT_SWAP"
CDS_LOCATION"C1D22"
CDS_LIB"dev_discrete"
MATERIAL"EMPTY"
LOCATION"C1D22"
PART_NUMBER"A36096-030"
VALUE"0.1UF"
PACK_TYPE"0402V"
TOLERANCE"10%"
VOLTAGE"16V";
"B"
$PN"2"54;
"A"
$PN"1"55;
%"RES"
"1","(250,3625)","0","mstr_discrete","I43";
;
$SEC"1"
CDS_SEC"1"
CDS_LIB"mstr_discrete"
CDS_LOCATION"R1D45"
ROOM"HOT_SWAP"
PACK_TYPE"0402"
LOCATION"R1D45"
TOLERANCE"5%"
PART_NUMBER"G21497-005"
MATERIAL"CHIP"
VALUE"0.0"
WATTAGE"1/16W";
"B"
$PN"2"71;
"A"
$PN"1"55;
%"RES"
"1","(225,3150)","0","mstr_discrete","I44";
;
CDS_SEC"1"
$SEC"1"
ROOM"HOT_SWAP"
CDS_LOCATION"R1D44"
CDS_LIB"mstr_discrete"
PACK_TYPE"0402"
TOLERANCE"5%"
LOCATION"R1D44"
WATTAGE"1/16W"
VALUE"0.0"
MATERIAL"CHIP"
PART_NUMBER"G21497-005";
"B"
$PN"2"72;
"A"
$PN"1"54;
%"RES"
"2","(875,2800)","0","mstr_discrete","I47";
;
ROOM"HOT_SWAP"
CDS_LOCATION"R9P27"
$SEC"1"
CDS_SEC"1"
CDS_LIB"mstr_discrete"
LOCATION"R9P27"
VALUE"10.0"
MATERIAL"CHIP"
TOLERANCE"1%"
PART_NUMBER"G21796-066"
PACK_TYPE"0402"
WATTAGE"1/16W";
"A"
$PN"1"59;
"B"
$PN"2"72;
%"RES"
"2","(750,2800)","2","mstr_discrete","I48";
;
$SEC"1"
CDS_SEC"1"
CDS_LOCATION"R1D46"
ROOM"HOT_SWAP"
CDS_LIB"mstr_discrete"
VALUE"10.0"
LOCATION"R1D46"
TOLERANCE"1%"
WATTAGE"1/16W"
MATERIAL"CHIP"
PART_NUMBER"G21796-066"
PACK_TYPE"0402";
"A"
$PN"1"58;
"B"
$PN"2"72;
%"RES_PWR"
"2","(1125,3200)","0","mstr_discrete","I49";
;
CDS_SEC"1"
SEC_TYPE"6PAD"
SEC"1"
ROOM"HOT_SWAP"
CDS_LOCATION"R9R1"
CDS_LIB"mstr_discrete"
CDS_LMAN_SYM_OUTLINE"-50,100,50,-100"
PART_NUMBER"E74391-005"
LOCATION"R9R1"
MATERIAL"CHIP"
PACK_TYPE"6PAD"
WATTAGE"3W"
VALUE"0.001"
TOLERANCE"1%";
"6"
$PN"6"69;
"5"
$PN"5"33;
"4"
$PN"4"60;
"3"
$PN"3"59;
"1"
$PN"1"33;
"2"
$PN"2"69;
%"RES_PWR"
"2","(1125,3600)","0","mstr_discrete","I50";
;
CDS_SEC"1"
ROOM"HOT_SWAP"
SEC"1"
SEC_TYPE"6PAD"
CDS_LOCATION"R1D49"
CDS_LMAN_SYM_OUTLINE"-50,100,50,-100"
CDS_LIB"mstr_discrete"
PART_NUMBER"E74391-005"
LOCATION"R1D49"
MATERIAL"CHIP"
TOLERANCE"1%"
PACK_TYPE"6PAD"
WATTAGE"3W"
VALUE"0.001";
"6"
$PN"6"69;
"5"
$PN"5"33;
"4"
$PN"4"68;
"3"
$PN"3"58;
"1"
$PN"1"33;
"2"
$PN"2"69;
%"RES"
"2","(1350,2800)","2","mstr_discrete","I51";
;
CDS_SEC"1"
$SEC"1"
CDS_LOCATION"R9P26"
ROOM"HOT_SWAP"
CDS_LIB"mstr_discrete"
TOLERANCE"1%"
PACK_TYPE"0402"
MATERIAL"CHIP"
PART_NUMBER"G21796-066"
VALUE"10.0"
WATTAGE"1/16W"
LOCATION"R9P26";
"A"
$PN"1"60;
"B"
$PN"2"71;
%"RES"
"2","(1475,2800)","0","mstr_discrete","I52";
;
ROOM"HOT_SWAP"
CDS_LOCATION"R1D47"
$SEC"1"
CDS_SEC"1"
CDS_LIB"mstr_discrete"
LOCATION"R1D47"
PART_NUMBER"G21796-066"
VALUE"10.0"
TOLERANCE"1%"
PACK_TYPE"0402"
MATERIAL"CHIP"
WATTAGE"1/16W";
"A"
$PN"1"68;
"B"
$PN"2"71;
%"P12V_PSU"
"1","(900,3825)","0","mstr_symbols","I53";
;
ROOM"P2V5_LAN_AUX_VR"
BOM_COST"NT_BASE_VRD"
CDS_LIB"mstr_symbols"
VOLTAGE"12.0"
BODY_TYPE"PLUMBING"
HDL_POWER"P12V_PSU";
"G\NAC"33;
%"MOSFETN_1D3S"
"1","(2275,3375)","1","mstr_discrete","I54";
;
CDS_SEC"1"
SEC"1"
SEC_TYPE"SOT5"
PACK_TYPE"SOT5"
CDS_LIB"mstr_discrete"
CDS_LOCATION"EU1E3"
ROOM"HOT_SWAP"
LOCATION"EU1E3"
MATERIAL"IC"
PART_NUMBER"G68777-001";
"D"
$PN"5"69;
"S3"
$PN"3"34;
"S1"
$PN"1"34;
"S2"
$PN"2"34;
"G"
$PN"4"63;
%"RES"
"1","(2000,3075)","0","mstr_discrete","I56";
;
CDS_SEC"1"
CDS_LIB"mstr_discrete"
SEC_TYPE"0402"
SEC"1"
CDS_LOCATION"R1E1"
ROOM"HOT_SWAP"
TOLERANCE"1%"
LOCATION"R1E1"
VALUE"10.0"
PACK_TYPE"0402"
MATERIAL"CHIP"
WATTAGE"1/16W"
PART_NUMBER"G21796-066";
"B"
$PN"2"63;
"A"
$PN"1"70;
%"MOSFETN_1D3S"
"1","(2300,2825)","1","mstr_discrete","I57";
;
CDS_SEC"1"
SEC"1"
SEC_TYPE"SOT5"
PACK_TYPE"SOT5"
ROOM"HOT_SWAP"
CDS_LOCATION"EU9R1"
CDS_LIB"mstr_discrete"
LOCATION"EU9R1"
PART_NUMBER"G68777-001"
MATERIAL"IC";
"D"
$PN"5"69;
"S3"
$PN"3"34;
"S1"
$PN"1"34;
"S2"
$PN"2"34;
"G"
$PN"4"62;
%"RES"
"1","(2000,2525)","0","mstr_discrete","I58";
;
ROOM"HOT_SWAP"
$SEC"1"
CDS_LOCATION"R9R4"
CDS_SEC"1"
CDS_LIB"mstr_discrete"
WATTAGE"1/16W"
PACK_TYPE"0402"
TOLERANCE"1%"
LOCATION"R9R4"
PART_NUMBER"G21796-066"
VALUE"10.0"
MATERIAL"CHIP";
"B"
$PN"2"62;
"A"
$PN"1"70;
%"MOSFETN_1D3S"
"1","(2275,2100)","1","mstr_discrete","I59";
;
CDS_SEC"1"
SEC"1"
SEC_TYPE"SOT5"
PACK_TYPE"SOT5"
ROOM"HOT_SWAP"
CDS_LOCATION"EU1E1"
CDS_LIB"mstr_discrete"
PART_NUMBER"G68777-001"
MATERIAL"IC"
LOCATION"EU1E1";
"D"
$PN"5"69;
"S3"
$PN"3"34;
"S1"
$PN"1"34;
"S2"
$PN"2"34;
"G"
$PN"4"61;
%"RES"
"1","(1950,1775)","0","mstr_discrete","I60";
;
CDS_SEC"1"
ROOM"HOT_SWAP"
CDS_LOCATION"R1D48"
SEC"1"
SEC_TYPE"0402"
CDS_LIB"mstr_discrete"
PART_NUMBER"G21796-066"
LOCATION"R1D48"
TOLERANCE"1%"
VALUE"10.0"
PACK_TYPE"0402"
MATERIAL"CHIP"
WATTAGE"1/16W";
"B"
$PN"2"61;
"A"
$PN"1"70;
%"P12V_STBY"
"1","(2525,3800)","0","mstr_symbols","I64";
;
SIZE"1B"
CDS_LIB"mstr_symbols"
VOLTAGE"12.0V"
BODY_TYPE"PLUMBING"
HDL_POWER"P12V_STBY";
"G\NAC"34;
%"RES"
"2","(-4400,-400)","0","mstr_discrete","I70";
;
CDS_SEC"1"
SEC_TYPE"0402"
SEC"1"
ROOM"HOT_SWAP"
CDS_LOCATION"R9P19"
CDS_LIB"mstr_discrete"
PART_NUMBER"G21796-016"
MATERIAL"EMPTY"
LOCATION"R9P19"
VALUE"10.0K"
TOLERANCE"1%"
WATTAGE"1/16W"
PACK_TYPE"0402";
"A"
$PN"1"48;
"B"
$PN"2"23;
%"RES"
"2","(-4400,250)","0","mstr_discrete","I71";
;
CDS_SEC"1"
SEC_TYPE"0402"
ROOM"HOT_SWAP"
SEC"1"
CDS_LOCATION"R9P21"
CDS_LIB"mstr_discrete"
PART_NUMBER"G21497-005"
TOLERANCE"5%"
LOCATION"R9P21"
VALUE"0.0"
MATERIAL"CHIP"
WATTAGE"1/16W"
PACK_TYPE"0402";
"A"
$PN"1"49;
"B"
$PN"2"48;
%"P3V3_STBY"
"1","(-3300,800)","0","mstr_symbols","I78";
;
CDS_LIB"mstr_symbols"
SIZE"1B"
VOLTAGE"3.3V"
BODY_TYPE"PLUMBING"
HDL_POWER"P3V3_STBY";
"G\NAC"35;
%"RES"
"2","(-3300,450)","0","mstr_discrete","I86";
;
CDS_SEC"1"
SEC"1"
SEC_TYPE"0402"
ROOM"HOT_SWAP"
CDS_LOCATION"R9P20"
CDS_LIB"mstr_discrete"
PART_NUMBER"G21796-344"
PACK_TYPE"0402"
MATERIAL"CHIP"
TOLERANCE"1%"
WATTAGE"1/16W"
VALUE"2.7K"
LOCATION"R9P20";
"A"
$PN"1"35;
"B"
$PN"2"74;
END.
